                    - SPARES  LIST -


                    - PART SUMMARY -

120R2F-GP_RCL_GP-120R2F-GP,64.A		51
18KR2F-GP_RCL_GP-18KR2F-GP,64.A		1
1K82R2F-1-GP_SMD-RG-1K82R2F-1-A		2
1MR2F-L-GP_SMD-RG1-1MR2F-L-GP,A		3
1R3F-GP_RCL_GP-1R3F-GP,64.1R00A		24
200R2F-L1-GP_SMD-RG4-200R2F-L1A		1
21K5R2F-GP_RCL_GP-21K5R2F-GP,6A		1
232KR2F-2-GP_SMD-RG1-232KR2F-2A		1
270KR2F-GP_RCL_GP-270KR2F-GP,6A		1
2K15R2F-1-GP_SMD-RG1-2K15R2F-1A		2
2SB2907A-B0-00001-GP_DISCRET-GA		2
374R2F-1-GP_SMD-RG-374R2F-1-GPA		5
47KR2F-GP_RCL_GP-47KR2F-GP,64.A		1
4D02R2F-GP_SMD-RG2-4D02R2F-GP,A		4
4K42R2F-GP_SMD-RG-4K42R2F-GP,6A		1
5K1R2F-2-GP_SMD-RG-5K1R2F-2-GPA		1
649R2F-GP_RCL_GP-649R2F-GP,64.A		1
665KR2B-GP_SMD-RG2-665KR2B-GP,A		4
665KR5B-1-GP_SMD-RG3-665KR5B-1A		8
74CBTLV1G125_SMLF-IC,C88177-00A	C88177-001	8
82KR2F-1-GP_SMD-RG-82KR2F-1-GPA		1
887R2F-L-GP_SMD-RG-887R2F-L-GPA		2
ADM1085_SMT-IC,H46130-001	H46130-001	1
ADM1278_SM-IC,G99251-001	G99251-001	1
ADM809_SMLF-IC,D23047-001-GND=A	D23047-001	2
AST2520A1-GP-GP_ASIC2-GB1-AST2A		1
AT24C64_SOICLF-IC,C47049-001-GA	C47049-001	2
BATTERY_PLCLF-202168-001	202168-001	1
BLM15AG121SN-1GP_DISCRET-G-BLMA		5
BLM31SN500SN1L-GP_DISCRET-GB1-A		1
BSL308C-H6327-GP_DISCRET-GB1-BA		4
CAPP_2626-270UF,16V,20%,OSCON,A	A31228-047	8
CAPP_3018-470UF,2.5V,20%,ALUM,A	699013-049	47
CAPP_3018-68UF,16V,20%,TANT,72A	724613-112	16
CAPP_4040LF-470UF,16V,20%,ALUMA	A93539-036	4
CAPP_7343-220UF,4V,20%,POSCAP,A	724613-067	4
CAPP_7343HLF-330UF,10V,20%,POSA	724613-043	1
CAPP_7343LF-330UF,6.3V,20%,POSA	724613-042	4
CAPP_SM-470UF,2V,20%,ALUM,6990A	699013-031	8
CAP_0402-0.027UF,16V,10%,X7R,AA	A36096-129	4
CAP_0402-0.047UF,25V,10%,X7R,AA	A36096-090	1
CAP_0402-0.220UF,16V,10%,X7R,AA	A36096-104	24
CAP_0402-0.22UF,16V,10%,X7R,A3A	A36096-155	241
CAP_0402-1.0UF,16V,10%,X6S,D97A	D97712-011	106
CAP_0402-1.0UF,16V,10%,X7S,G71A	G71842-007	1
CAP_0402-1.0UF,6.3V,10%,EMPTY,A	D97712-004	1
CAP_0402LF-0.022UF,16V,10%,X7RA	A36096-073	1
CAP_0402LF-0.039UF,25V,10%,X7RA	A36096-063	1
CAP_0402LF-10.0PF,50V,5%,COG,AA	A36094-025	3
CAP_0402LF-100.0PF,50V,5%,COG,A	A36095-026	8
CAP_0402LF-1000PF,50V,10%,EMPTA	A36096-046	14
CAP_0402LF-1000PF,50V,10%,X7R,A	A36096-046	72
CAP_0402LF-12.0PF,50V,5%,COG,AA	A36095-043	6
CAP_0402LF-15.0PF,50V,5%,COG,AA	A36095-047	8
CAP_0402LF-2200PF,50V,10%,X7R,A	A36096-075	9
CAP_0402LF-220PF,50V,10%,X7R,AA	A36096-050	24
CAP_0402LF-270PF,50V,10%,X7R,AA	A36096-065	1
CAP_0402LF-33.0PF,50V,5%,COG,AA	A36095-031	2
CAP_0402LF-3300PF,50V,10%,EMPTA	A36096-091	5
CAP_0402LF-47.0PF,50V,5%,COG,AA	A36095-025	11
CAP_0402LF-47.0PF,50V,5%,EMPTYA	A36095-025	2
CAP_0402LF-4700PF,50V,10%,EMPTA	A36096-066	4
CAP_0402LF-470PF,50V,10%,EMPTYA	A36096-049	2
CAP_0402LF-470PF,50V,10%,X7R,AA	A36096-049	4
CAP_0603-10UF,6.3V,20%,X6S,E15A	E15431-002	26
CAP_0603-4.7UF,6.3V,10%,X6S,E1A	E15431-003	18
CAP_0603LF-0.033UF,50V,10%,X7RA	603269-064	2
CAP_0603LF-0.1UF,25V,10%,X7R,6A	602433-020	7
CAP_0603LF-10UF,4V,20%,X6S,E15A	E15431-001	74
CAP_0805-100UF,4V,20%,X5R,6024A	602433-112	104
CAP_0805-10UF,16V,10%,EMPTY,C9A	C95333-007	1
CAP_0805-10UF,16V,10%,X6S,C953A	C95333-007	108
CAP_0805-10UF,16V,10%,X7R,G106A	G10601-001	13
CAP_0805-22UF,6.3V,20%,X6S,C95A	C95333-008	5
CAP_0805-47UF,4V,20%,X6S,C9533A	C95333-006	67
CAP_0805LF-22UF,4V,20%,X6S,C95A	C95333-002	23
CAP_1206-0.068UF,50V,20%,X7R,1A	108427-047	1
CAP_1206LF-22UF,16V,10%,X6S,D3A	D38464-005	3
CAP_A_0402V-0.01UF,25V,10%,X7RA	A36096-045	98
CAP_A_0402V-0.1UF,16V,10%,EMPTA	A36096-030	6
CAP_A_0402V-0.1UF,16V,10%,X7R,A	A36096-030	308
CAP_A_0402V-1.0UF,6.3V,10%,X6SA	D97712-004	113
CAP_A_0603V-22.0UF,4V,20%,EMPTA	E15431-004	2
CAP_A_0603V-22.0UF,4V,20%,X6S,A	E15431-004	285
CAP_A_0603V-47UF,4V,20%,X5R,60A	602433-106	172
CHOKE_4PIN_SMLF-90 OHM,IND,752A	752402-015	1
CHOKE_4PIN_SM_B-67 OHM,EMPTY,7A	752402-028	2
CLX-CONN3A-1-GP_CONN-G3-CLX-COA		1
CONN12_C73564003_PIP-CONN,C735A	C73564-003	3
CONN14_H54902001_PIP-CONN,H549A	H54902-001	1
CONN3_C95678002_PIP-CONN,C9567A	C95678-002	2
CONN3_G98259001_PIP-CONN,G9825A	G98259-001	1
CONN4_D42317002_PIP-CONN,D4231A	D42317-002	1
CONN6_C74770005_PIP-HDR,C74770A	C74770-005	1
CONN72_G97614002_A_CP-CONN,G97A	G97614-002	1
CONN8_C77962004_PIP-CONN,C7796A	C77962-004	1
CONN8_H62179001_PIP-CONN,H6217A	H62179-001	1
CONN9_H51826001_PIP2-CONN,H518A	H51826-001	1
CRYSTAL_2013-25.000MHZ,IC,D717A	D71700-057	1
CRYSTAL_2013-25.000MHZ,IC,H196A	H19611-001	1
CRYSTAL_2013-48.000MHZ,IC,D717A	D71700-058	1
CRYSTAL_2013LF-25.000MHZ,IC,D7B	D71700-033	1
CRYSTAL_SM-32.768KHZ,IC,C13544A	C13544-023	1
CSD87384M_SM-IC,H66258-001	H66258-001	1
DIODE2A_DUAL_SMLF-BAS70-05,DIOA	C90169-001	1
DIODEAC_DUAL_ARRAY_SM9-ESD3V3UA	G18435-001	4
DIODE_SM-1N4148W,IC,D89194-001	D89194-001	4
DIODE_SM-MBRS340T3G,EMPTY,C819A	C81983-002	1
DIODE_SM-SDMK0340L,EMPTY,H7179A	H71799-001	3
DIODE_SM-SDMK0340L,IC,H71799-0A	H71799-001	6
DIODE_SMLF-1N5819HW,IC,D55839-A	D55839-001	1
DIODE_SMLF-BAT54WS,IC,C73510-0A	C73510-001	8
DM-FCI-CONN76-8R-GP-U-01_CONN-A		2
FCI-CONN12-2R-GP_CONN-G5-FCI-CA		2
FERRITE_SM-120,FB,693286-027	693286-027	6
FERRITE_SM-22,FB,656554-051	656554-051	5
FERRITE_SMLF-30,FB,693286-021	693286-021	2
FERRITE_SMLF-600,FB,656554-043	656554-043	2
FET_N_DUAL_SMLF-2N7002DW,FET,DA	D24280-001	7
FET_N_DUAL_SMLF-NTJD4001N,FET,A	E40049-001	15
FET_N_SOT23LF-2N7002,FET,C7925A	C79254-001	20
FSA3357_SM-IC,C63273-001	C63273-001	2
FUSE-3A75V-GP_DISCRET-G5-FUSE-A		1
FUSE_SM-IC,C94311-016	C94311-016	1
FUSE_SMT-IC,H45581-001	H45581-001	1
GTL2014_SM-IC,D66151-001	D66151-001	8
H5AN4G6NAFR-TFC-GP_MEMORY-G2-HA		1
HCB1608KF-800T30-GP_DISCRET-G9A		5
ICS9FGP204_MLFP-IC,E95226-001	E95226-001	1
IND-100NH-35-GP_DISCRET-G8-INDA		5
IND-120NH-30-GP_DISCRET-GB2-INA		18
IND-150NH-56-GP_DISCRET-GA1-INA		2
IND-1UH-361-GP_DISCRET-GC1-INDA		1
IND-300NH-20-GP_DISCRET-GB1-INA		4
IND-68NH-15-GP_DISCRET-GC1-INDA		3
IND-80NH-1-GP_DISCRET-GC2-IND-A		2
INDUCTOR_SM-0.47UH,IND,E13358-A	E13358-018	4
INDUCTOR_SM-2.2UH,IND,E98761-0A	E98761-003	1
INDUCTOR_SMT-0.022UH,IND,72189A	721891-082	1
IR354XX_SM-IR35411,IC,H73688-0A	H73688-001	18
IR354XX_SM-IR35412,IC,H73684-0A	H73684-001	6
LBG_CORE_QAT_EXT_D_BGA1-IC,H91A	H91415-002	1
LCMXO2_A_256BGA-IC,H63395-001	H63395-001	1
LED_1NC-BLUE,IC,C96565-012	C96565-012	1
LED_1NCLF-GREEN,IC,C96565-011	C96565-011	1
LED_1NCLF-YELLOW,IC,C96565-003	C96565-003	1
LED_A1-RED,IC,D14725-005	D14725-005	1
LED_A1LF-GREEN,IC,C97278-010	C97278-010	3
LED_A1LF-GREEN,IC,D14725-022	D14725-022	2
LMV331IDCKRG4-GP_DISCRET-G-LMVA		1
LMV431AIMFX-GP_DISCRET-G5-LMV4A		1
LOTES-CON4-S1-GP_CONN-G7-LOTESA		2
M25PE16_SM-IC,H77797-001	H77797-001	1
MAX4564EKA-GP_SCRET-GC1-MAX456A		1
MIC5166_DFN-IC,H55101-001	H55101-001	4
MOSFETN_1D3S_SOT5-IC,G68777-001	G68777-001	3
MOSFET_N_LCC3-BSZ019N03LS,NFETA	G26762-001	4
MTG_KEYHOLE_TH-EMPTY,NA	NA	7
NB3W1200L_LCC-IC,H13585-001	H13585-001	1
NC7SB3157_SMLF-IC,C99406-001	C99406-001	5
NCP3232L_SM-IC,H86355-001	H86355-001	4
NPN_DUAL_SSOPLF-MBT3904,EMPTY,A	C52264-001	1
NPN_DUAL_SSOPLF-MBT3904,XSTR,CA	C52264-001	2
NPN_SM-MMBT3904,IC,C52245-001	C52245-001	9
OSC_C_6P10-156.25MHZ,OSC,G6383A	G63831-004	2
OSC_C_SM4-24MHZ,OSC,D34520-021	D34520-021	1
PCA9554PWR-GP_DISCRET-G1-PCA95A		1
PCA9617_SSOP-IC,G81764-001-GNDA	G81764-001	5
PI3B3257A_TSSOPLF-IC,E16801-001	E16801-001	2
PI5A3157BC6E-GP_DISCRET-GC2-PIA		1
PIN-CON3-27-GP_CONN-G7-PIN-CONA		1
POLYSW-1D1A6V-2-GP-U_DISCRET-GA		1
POLYSW-D5A6V-2-GP-U_DISCRET-GAA		1
PXE1110B_QFN-IC,H89187-001	H89187-001	3
PXE1610B_QFN-IC,H79206-001	H79206-001	2
PXM1310B_QFN-IC,H89186-001	H89186-001	4
RB551V30-GP_DISCRET-G-RB551V30A		1
RES_0402-0.0,5%,1/16W,CHIP,G21A	G21497-005	354
RES_0402-0.0,5%,1/16W,EMPTY,G2A	G21497-005	77
RES_0402-1.00K,1%,1/16W,CHIP,GA	G21796-026	160
RES_0402-1.00K,1%,1/16W,EMPTY,A	G21796-026	26
RES_0402-1.0K,0.1%,1/16W,CHIP,A	G85996-004	32
RES_0402-1.0M,1%,1/16W,EMPTY,GA	G21796-021	5
RES_0402-1.37K,1%,1/16W,CHIP,GA	G21796-095	5
RES_0402-1.5K,1%,1/16W,CHIP,G2A	G21796-003	8
RES_0402-1.8K,1%,1/16W,CHIP,G2A	G21796-336	8
RES_0402-10.0,1%,1/16W,CHIP,G2A	G21796-066	46
RES_0402-10.0,1%,1/16W,EMPTY,GA	G21796-066	2
RES_0402-10.0K,1%,1/16W,CHIP,GA	G21796-016	110
RES_0402-10.0K,1%,1/16W,EMPTY,A	G21796-016	17
RES_0402-100.0,1%,1/16W,CHIP,GA	G21796-017	52
RES_0402-100.0,1%,1/16W,EMPTY,A	G21796-017	10
RES_0402-100.0K,1%,1/16W,CHIP,A	G21796-010	34
RES_0402-100.0K,1%,1/16W,CHIP,B	G21796-160	5
RES_0402-100.0K,1%,1/16W,EMPTYA	G21796-010	8
RES_0402-105.0K,1%,1/16W,CHIP,A	G21796-099	1
RES_0402-110,1%,1/16W,EMPTY,G2A	G21796-203	1
RES_0402-113,1%,1/16W,CHIP,G21A	G21796-341	1
RES_0402-11K,1%,1/16W,CHIP,G21A	G21796-220	1
RES_0402-12.1K,1%,1/16W,CHIP,GA	G21796-089	1
RES_0402-15.0K,1%,1/16W,CHIP,GA	G21796-107	2
RES_0402-150.0,1%,1/16W,CHIP,GA	G21796-009	42
RES_0402-150.0K,1%,1/16W,CHIP,A	G21796-109	1
RES_0402-169,1.0%,1/16W,CHIP,GA	G21796-276	1
RES_0402-16K,1.0%,1/16W,CHIP,GA	G21796-317	4
RES_0402-2,1.0%,1/16W,CHIP,G21A	G21796-274	12
RES_0402-2.0K,1%,1/16W,CHIP,G2A	G21796-001	18
RES_0402-2.0K,1%,1/16W,EMPTY,GA	G21796-001	2
RES_0402-2.2,5%,1/16W,EMPTY,G2A	G21497-016	5
RES_0402-2.21K,1%,1/16W,CHIP,GA	G21796-112	14
RES_0402-2.26K,1.0%,1/16W,CHIPA	G21796-311	12
RES_0402-2.26K,1.0%,1/16W,EMPTA	G21796-311	9
RES_0402-2.67K,1%,1/16W,CHIP,GA	G21796-180	1
RES_0402-2.7K,1%,1/16W,CHIP,G2A	G21796-344	12
RES_0402-2.7K,1%,1/16W,EMPTY,GA	G21796-344	1
RES_0402-20.0,1%,1/16W,CHIP,G2A	G21796-173	54
RES_0402-20.0,1%,1/16W,EMPTY,GA	G21796-173	4
RES_0402-20.0K,1%,1/16W,CHIP,GA	G21796-040	11
RES_0402-200.0,1%,1/16W,CHIP,GA	G21796-004	11
RES_0402-200.0K,1%,1/16W,CHIP,A	G21796-080	2
RES_0402-22.1,1.0%,1/16W,CHIP,A	G21796-250	36
RES_0402-221,1.0%,1/16W,CHIP,GA	G21796-271	11
RES_0402-23.2K,1%,1/16W,CHIP,GA	G21796-114	1
RES_0402-24.9K,1%,1/16W,CHIP,GA	G21796-254	1
RES_0402-240,1.0%,1/16W,CHIP,GA	G21796-294	21
RES_0402-240,1.0%,1/16W,EMPTY,A	G21796-294	19
RES_0402-249,0.1%,1/16W,CHIP,GA	G85996-031	2
RES_0402-27.4,1%,1/16W,CHIP,G2A	G21796-182	24
RES_0402-3.16K,1%,1/16W,CHIP,GA	G21796-043	7
RES_0402-3.32K,1%,1/16W,CHIP,GA	G21796-027	4
RES_0402-3.32K,1%,1/16W,EMPTY,A	G21796-027	5
RES_0402-3.3K,5%,1/16W,CHIP,G2A	G21497-013	7
RES_0402-3.48K,1.0%,1/16W,CHIPA	G21796-279	2
RES_0402-3.74K,1%,1/16W,CHIP,GA	G21796-059	1
RES_0402-301.0,1%,1/16W,CHIP,GA	G21796-076	1
RES_0402-33.0K,5%,1/16W,CHIP,GA	G21497-023	1
RES_0402-33.2,1%,1/16W,CHIP,G2A	G21796-074	90
RES_0402-33.2,1%,1/16W,EMPTY,GA	G21796-074	2
RES_0402-330,5%,1/16W,CHIP,G21A	G21497-028	4
RES_0402-348,1%,1/16W,CHIP,G21A	G21796-340	1
RES_0402-348,1%,1/16W,EMPTY,G2A	G21796-340	1
RES_0402-4.02K,1%,1/16W,CHIP,GA	G21796-082	7
RES_0402-4.75K,1%,1/16W,CHIP,GA	G21796-072	166
RES_0402-4.75K,1%,1/16W,EMPTY,A	G21796-072	37
RES_0402-4.99K,1%,1/16W,CHIP,GA	G21796-013	2
RES_0402-40.2K,1%,1/16W,CHIP,GA	G21796-133	2
RES_0402-42.2,1.0%,1/16W,EMPTYA	G21796-259	24
RES_0402-470.0,5%,1/16W,CHIP,GA	G21497-024	1
RES_0402-475.0,1%,1/16W,CHIP,GA	G21796-077	2
RES_0402-49.9,1%,1/16W,CHIP,G2A	G21796-047	57
RES_0402-49.9,1%,1/16W,EMPTY,GA	G21796-047	9
RES_0402-49.9K,1%,1/16W,CHIP,GA	G21796-048	5
RES_0402-5.11K,1%,1/16W,CHIP,GA	G21796-140	6
RES_0402-5.36K,1.0%,1/16W,CHIPA	G21796-297	1
RES_0402-51,5.0%,1/16W,CHIP,G2A	G21497-048	4
RES_0402-51.1,1.0%,1/16W,CHIP,A	G21796-208	7
RES_0402-6.19K,1%,1/16W,CHIP,GA	G21796-161	6
RES_0402-6.34K,1%,1/16W,CHIP,GA	G21796-146	1
RES_0402-63.4K,1.0%,1/16W,CHIPA	G21796-327	1
RES_0402-64.9,1.0%,1/16W,CHIP,A	G21796-298	5
RES_0402-665,1.0%,1/16W,CHIP,GA	G21796-235	18
RES_0402-68.1K,1%,1/16W,EMPTY,A	G21796-187	24
RES_0402-69.8K,1%,1/16W,CHIP,GA	G21796-007	1
RES_0402-7.5K,1%,1/16W,CHIP,G2A	G21796-177	1
RES_0402-7.87K,1.0%,1/16W,CHIPA	G21796-242	8
RES_0402-75,1.0%,1/16W,CHIP,G2A	G21796-267	8
RES_0402-75K,1%,1/16W,CHIP,G21A	G21796-224	1
RES_0402-8.06K,1%,1/16W,CHIP,GA	G21796-078	1
RES_0402-8.2K,1%,1/16W,CHIP,G2A	G21796-345	2
RES_0402-8.2K,1%,1/16W,EMPTY,GA	G21796-345	1
RES_0402-90.9,1%,1/16W,CHIP,G2A	G21796-365	8
RES_0402-90.9K,1%,1/16W,CHIP,GA	G21796-058	2
RES_0603-0,5.0%,1/10W,CHIP,G22A	G22178-002	33
RES_0603-0,5.0%,1/10W,EMPTY,G2A	G22178-002	1
RES_0603-10.0,1%,1/10W,CHIP,G2A	G22026-041	2
RES_0603-100.0,1%,1/10W,CHIP,GA	G22026-038	2
RES_0603-100.0K,1%,1/10W,CHIP,A	G22026-050	7
RES_0603-10M,1.0%,1/10W,CHIP,GA	G22026-112	1
RES_0603-120.0,1%,1/10W,CHIP,GA	G22026-003	8
RES_0603-2.2,1.0%,1/10W,CHIP,GA	G22026-127	5
RES_0603-200K,0.1%,1/10W,CHIP,A	G22369-010	1
RES_0603-475.0,1%,1/10W,CHIP,GA	G22026-030	1
RES_0805-0.0,5%,1/8W,CHIP,G221A	G22179-004	3
RES_0805-0.0,5%,1/8W,EMPTY,G22A	G22179-004	1
RES_1206-0.002,1%,1W,CHIP,G521A	G52199-004	4
RES_PWR_6PAD-0.001,1%,3W,CHIP,A	E74391-005	2
RT8240_QFN-IC,H66262-001	H66262-001	1
RT9059_DFN-IC,H65765-001	H65765-001	4
SC1U10V2KX-4-GP_SMD-BCG6-SC1U1A		25
SC1U16V3KX-2GP_SMD-BCG-SC1U16VA		3
SC22P50V2JN-4GP_SMD-BCG-SC22P5A		26
SC22U16V5MX-4-GP_SMD-BCG5-SC22A		71
SC4D7U16V3KX-GP_SMD-BCG5-SC4D7A		1
SCONN10_C12536004_SMLF-CONN,C1A	C12536-004	1
SCONN11_H67026001_SM-CONN,H670A	H67026-001	1
SCONN120_A28699018_SM-SCONN,A2A	A28699-018	1
SCONN120_H61426002_SM-CONN,H61A	H61426-002	4
SCONN200_H68296001_SM-CONN,H68A	H68296-001	1
SCONN24_H46321001_SM-SCONN,H46A	H46321-001	1
SCONN288_H44441003_PIP-SCONN,HA	H44441-003	12
SCONN288_H44441004_PIP-SCONN,HA	H44441-004	12
SCONN60_C21100002_SMLF-CONN,C2A	C21100-002	1
SCONN64_H87568002_A_SMT-CONN,HA	H87568-002	1
SCONN80_E67482007_SM-CONN,E674A	E67482-007	1
SE100U16VM-48-GP_SMD-TCG2-SE10A		1
SHUNT_SH0201-EMPTY,N_A	N_A	16
SKT-MINI67P-41-GP_SOCKET-G4-SKA		1
SKT-RJ45-LED-XFOR-1-GP_SOCKET-A		1
SKT-SATA7P-6P-165-GP-U1_SOCKETA		2
SKT-USB32-8-GP_SOCKET-G4-SKT-UA		1
SKX_EXT_B_BGA1-IC,TBD	TBD	2
SLG55021_SM-IC,G56246-001	G56246-001	4
SMC-CON13-GP_CONN-GC2-SMC-CON1A		1
SMC-CONN60A-22-GP_CONN-G7-SMC-A		1
SN74LVC2G07DCKR-GP_DISCRET-G4-A		2
SOCKET_P_MECH_A_LEFT-P0,PLASTIA	H37604-201	2
SOCKET_P_MECH_A_RIGHT-P0,PLASTA	H37604-101	2
SPRINGVILLE_SM1-IC,G47144-004	G47144-004	1
ST220U10VDM-LGP_SMD-TCG-ST220UA		1
ST270U2D5VBM-GP_SMD-TCG2-ST270A		3
ST470U6D3VDM-7-GP_SMD-TCG4-ST4A		2
STANDOFF_TH1-SO,H72821-001	H72821-001	1
STFT363B238R224H453-GP_DISCRETA		1
SW-SLIDE75-GP_DISCRET-G6-SW-SLA		1
SWITCH_D37771002_SM-IC,D37771-A	D37771-002	2
SWITCH_D90553001_SMLF-IC,D9055A	D90553-001	1
TC7PZ14FU-GP_DISCRET-GA1-TC7PZA		3
TCA9517DGKR-GP_DISCRET-G8-TCA9A		5
TCA9555PWR-GP_DISCRET-GC1-TCA9A		1
TEST-PAD-12P-1-GP-U_DISCRET-GBA		24
TMP421_TSSOP-IC,G62962-001	G62962-001	2
TPAD-DIFF-4P-GP_DISCRET-GB3-TPA		18
TPAD-SE-2P-GP_DISCRET-GA1-TPADA		12
TPS2061_SM-IC,H66405-001	H66405-001	1
TPS3700_SM-IC,H69492-001	H69492-001	4
TPS54821_LCC-IC,H63269-001	H63269-001	1
TTL08_QFN15-74LVC08A,IC,D90404B	D90404-001	1
TTL1G07_A_SOP-74LVC1G07,IC,C88B	C88419-001	13
TTL1G08_SOTLF-NC7SZ08,IC,D1032B	D10321-001	5
TTL1G08_SOTLF-NC7SZ08,IC,D1032C	D10321-001	3
TTL1G126_A_SOT-74HC1G126,IC,A7B	A79322-001	9
TTL1G32_A_SOT-74LVC1G32,IC,E60B	E60229-001	2
TTL1G86_SOTLF-74AHCT1G86,IC,D3B	D39848-001	1
TTL3126_QFNLF-74CBTLV3126,IC,DB	D18317-001	5
U74AHCT1G125G-AL5-R-GP-U_TTL-GA		2
VERT_BATT_3PIN_PIP-3PVERT,C686A	C68619-005	1
W25Q128_SKT16-IC,H12709-001	H12709-001	1
W25Q256FVFIG-GP_MEMORY-G4-W25QA		1
W25Q256_XSOI-IC,H25002-001	H25002-001	2
ZENER_SM-13V,IC,H69095-001	H69095-001	1

Total                                    4751
